# T6G (Grand Teton) — schematic netlist excerpt (pin names and nets, part order shuffled) for the footprints in the layout excerpt that follows; sources: Cadence DE-HDL packaged netlist, KiCad conversion of 04192023_DAF0TMB3IC0_F0TG_MB_C_brd_V02_OCP.brd

J20  SCONN288_DDR506112002KQ  IO  pkg DDR288S_1-1VXC  page 96
  VIN_BULK0  = P12V_MEM_CPU0
  RFU0  = NC
  VIN_MGMT  = P3V3_AUX
  HSCL  = I3C_SPD_DDRK_CPU0_SCL
  HSDA  = I3C_SPD_DDRK_CPU0_SDA
  VSS0  = GND
  DQ0_A  = M_K_CPU0_SA_DQ<0>
  VSS1  = GND
  DQ1_A  = M_K_CPU0_SA_DQ<1>
  VSS2  = GND
  DQS0_A_T  = M_K_CPU0_SA_DQS_DP<0>
  DQS0_A_C  = M_K_CPU0_SA_DQS_DN<0>
  VSS3  = GND
  DQ4_A  = M_K_CPU0_SA_DQ<4>
  VSS4  = GND
  DQ5_A  = M_K_CPU0_SA_DQ<5>
  VSS5  = GND
  DQ8_A  = M_K_CPU0_SA_DQ<8>
  VSS6  = GND
  DQ9_A  = M_K_CPU0_SA_DQ<9>
  VSS7  = GND
  DQS1_A_T  = M_K_CPU0_SA_DQS_DP<1>
  DQS1_A_C  = M_K_CPU0_SA_DQS_DN<1>
  VSS8  = GND
  DQ12_A  = M_K_CPU0_SA_DQ<12>
  VSS9  = GND
  DQ13_A  = M_K_CPU0_SA_DQ<13>
  VSS10  = GND
  DQ16_A  = M_K_CPU0_SA_DQ<16>
  VSS11  = GND
  DQ17_A  = M_K_CPU0_SA_DQ<17>
  VSS12  = GND
  DQS2_A_T  = M_K_CPU0_SA_DQS_DP<2>
  DQS2_A_C  = M_K_CPU0_SA_DQS_DN<2>
  VSS13  = GND
  DQ20_A  = M_K_CPU0_SA_DQ<20>
  VSS14  = GND
  DQ21_A  = M_K_CPU0_SA_DQ<21>
  VSS15  = GND
  DQ24_A  = M_K_CPU0_SA_DQ<24>
  VSS16  = GND
  DQ25_A  = M_K_CPU0_SA_DQ<25>
  VSS17  = GND
  DQS3_A_T  = M_K_CPU0_SA_DQS_DP<3>
  DQS3_A_C  = M_K_CPU0_SA_DQS_DN<3>
  VSS18  = GND
  DQ28_A  = M_K_CPU0_SA_DQ<28>
  VSS19  = GND
  DQ29_A  = M_K_CPU0_SA_DQ<29>
  VSS20  = GND
  CB0_A  = M_K_CPU0_SA_CB<0>
  VSS21  = GND
  CB1_A  = M_K_CPU0_SA_CB<1>
  VSS22  = GND
  DQS4_A_T  = M_K_CPU0_SA_DQS_DP<4>
  DQS4_A_C  = M_K_CPU0_SA_DQS_DN<4>
  VSS23  = GND
  CB4_A  = M_K_CPU0_SA_CB<4>
  VSS24  = GND
  CB5_A  = M_K_CPU0_SA_CB<5>
  VSS25  = GND
  ALERT_N  = M_K_CPU0_ALERT_N
  VSS26  = GND
  CS0_A_N  = M_K_CPU0_SA_CS_N<0>
  VSS27  = GND
  CA0_A  = M_K_CPU0_SA_CA<0>
  VSS28  = GND
  CA2_A  = M_K_CPU0_SA_CA<2>
  VSS29  = GND
  CA4_A  = M_K_CPU0_SA_CA<4>
  VSS30  = GND
  CA6_A  = M_K_CPU0_SA_CA<6>
  VSS31  = GND
  PAR_A  = M_K_CPU0_SA_PAR
  VSS32  = GND
  CA0_B  = M_K_CPU0_SB_CA<0>
  VSS33  = GND
  CA2_B  = M_K_CPU0_SB_CA<2>
  VSS34  = GND
  CA4_B  = M_K_CPU0_SB_CA<4>
  VSS35  = GND
  CA6_B  = M_K_CPU0_SB_CA<6>
  VSS36  = GND
  CS0_B_N  = M_K_CPU0_SB_CS_N<0>
  VSS37  = GND
  \lbd||rsp_a_n\  = M_K_CPU0_SA_RSP<0>
  \lbs||rsp_b_n\  = M_K_CPU0_SB_RSP<0>
  VSS38  = GND
  CB4_B  = M_K_CPU0_SB_CB<4>
  VSS39  = GND
  CB5_B  = M_K_CPU0_SB_CB<5>
  VSS40  = GND
  \dqs9_b_t||tdqs9_b_t||dbi4_b_n\  = M_K_CPU0_SB_DQS_DP<9>
  \dqs9_b_c||tdqs9_b_c\  = M_K_CPU0_SB_DQS_DN<9>
  VSS41  = GND
  CB0_B  = M_K_CPU0_SB_CB<0>
  VSS42  = GND
  CB1_B  = M_K_CPU0_SB_CB<1>
  VSS43  = GND
  DQ0_B  = M_K_CPU0_SB_DQ<0>
  VSS44  = GND
  DQ1_B  = M_K_CPU0_SB_DQ<1>
  VSS45  = GND
  DQS0_B_T  = M_K_CPU0_SB_DQS_DP<0>
  DQS0_B_C  = M_K_CPU0_SB_DQS_DN<0>
  VSS46  = GND
  DQ4_B  = M_K_CPU0_SB_DQ<4>
  VSS47  = GND
  DQ5_B  = M_K_CPU0_SB_DQ<5>
  VSS48  = GND
  DQ8_B  = M_K_CPU0_SB_DQ<8>
  VSS49  = GND
  DQ9_B  = M_K_CPU0_SB_DQ<9>
  VSS50  = GND
  DQS1_B_T  = M_K_CPU0_SB_DQS_DP<1>
  DQS1_B_C  = M_K_CPU0_SB_DQS_DN<1>
  VSS51  = GND
  DQ12_B  = M_K_CPU0_SB_DQ<12>
  VSS52  = GND
  DQ13_B  = M_K_CPU0_SB_DQ<13>
  VSS53  = GND
  DQ16_B  = M_K_CPU0_SB_DQ<16>
  VSS54  = GND
  DQ17_B  = M_K_CPU0_SB_DQ<17>
  VSS55  = GND
  DQS2_B_T  = M_K_CPU0_SB_DQS_DP<2>
  DQS2_B_C  = M_K_CPU0_SB_DQS_DN<2>
  VSS56  = GND
  DQ20_B  = M_K_CPU0_SB_DQ<20>
  VSS57  = GND
  DQ21_B  = M_K_CPU0_SB_DQ<21>
  VSS58  = GND
  DQ24_B  = M_K_CPU0_SB_DQ<24>
  VSS59  = GND
  DQ25_B  = M_K_CPU0_SB_DQ<25>
  VSS60  = GND
  DQS3_B_T  = M_K_CPU0_SB_DQS_DP<3>
  DQS3_B_C  = M_K_CPU0_SB_DQS_DN<3>
  VSS61  = GND
  DQ28_B  = M_K_CPU0_SB_DQ<28>
  VSS62  = GND
  DQ29_B  = M_K_CPU0_SB_DQ<29>
  VSS63  = GND
  RFU1  = NC
  VIN_BULK1  = P12V_MEM_CPU0
  VIN_BULK2  = P12V_MEM_CPU0
  \pwr_good||fail_n\  = PWRGD_CHK_CPU0_DIMM
  HAS  = PD_CHK_CPU0_DIMM_SAA
  RFU2  = NC
  RFU3  = NC
  VSS64  = GND
  DQ2_A  = M_K_CPU0_SA_DQ<2>
  VSS65  = GND
  DQ3_A  = M_K_CPU0_SA_DQ<3>
  VSS66  = GND
  \dqs5_a_c||tdqs5_a_c||dqs5_a_t||tdqs5_a_t\  = M_K_CPU0_SA_DQS_DN<5>
  \dqs5_a_t||tdqs5_a_t\  = M_K_CPU0_SA_DQS_DP<5>
  VSS67  = GND
  DQ6_A  = M_K_CPU0_SA_DQ<6>
  VSS68  = GND
  DQ7_A  = M_K_CPU0_SA_DQ<7>
  VSS69  = GND
  DQ10_A  = M_K_CPU0_SA_DQ<10>
  VSS70  = GND
  DQ11_A  = M_K_CPU0_SA_DQ<11>
  VSS71  = GND
  \dqs6_a_c||tdqs6_a_c||dqs6_a_t||tdqs6_a_t\  = M_K_CPU0_SA_DQS_DN<6>
  \dqs6_a_t||tdqs6_a_t\  = M_K_CPU0_SA_DQS_DP<6>
  VSS72  = GND
  DQ14_A  = M_K_CPU0_SA_DQ<14>
  VSS73  = GND
  DQ15_A  = M_K_CPU0_SA_DQ<15>
  VSS74  = GND
  DQ18_A  = M_K_CPU0_SA_DQ<18>
  VSS75  = GND
  DQ19_A  = M_K_CPU0_SA_DQ<19>
  VSS76  = GND
  \dqs7_a_c||tdqs7_a_c\  = M_K_CPU0_SA_DQS_DN<7>
  \dqs7_a_t||tdqs7_a_t\  = M_K_CPU0_SA_DQS_DP<7>
  VSS77  = GND
  DQ22_A  = M_K_CPU0_SA_DQ<22>
  VSS78  = GND
  DQ23_A  = M_K_CPU0_SA_DQ<23>
  VSS79  = GND
  DQ26_A  = M_K_CPU0_SA_DQ<26>
  VSS80  = GND
  DQ27_A  = M_K_CPU0_SA_DQ<27>
  VSS81  = GND
  \dqs8_a_c||tdqs8_a_c\  = M_K_CPU0_SA_DQS_DN<8>
  \dqs8_a_t||tdqs8_a_t\  = M_K_CPU0_SA_DQS_DP<8>
  VSS82  = GND
  DQ30_A  = M_K_CPU0_SA_DQ<30>
  VSS83  = GND
  DQ31_A  = M_K_CPU0_SA_DQ<31>
  VSS84  = GND
  CB2_A  = M_K_CPU0_SA_CB<2>
  VSS85  = GND
  CB3_A  = M_K_CPU0_SA_CB<3>
  VSS86  = GND
  \dqs9_a_c||tdqs9_a_c\  = M_K_CPU0_SA_DQS_DN<9>
  \dqs9_a_t||tdqs9_a_t\  = M_K_CPU0_SA_DQS_DP<9>
  VSS87  = GND
  CB6_A  = M_K_CPU0_SA_CB<6>
  VSS88  = GND
  CB7_A  = M_K_CPU0_SA_CB<7>
  VSS89  = GND
  RESET_N  = M_K_CPU0_RESET_N
  VSS90  = GND
  CS1_A_N  = M_K_CPU0_SA_CS_N<1>
  VSS91  = GND
  CA1_A  = M_K_CPU0_SA_CA<1>
  VSS92  = GND
  CA3_A  = M_K_CPU0_SA_CA<3>
  VSS93  = GND
  CA5_A  = M_K_CPU0_SA_CA<5>
  VSS94  = GND
  CK_T  = M_K_CPU0_CLK_DP<0>
  CK_C  = M_K_CPU0_CLK_DN<0>
  VSS95  = GND
  RFU4  = NC
  CA1_B  = M_K_CPU0_SB_CA<1>
  VSS96  = GND
  CA3_B  = M_K_CPU0_SB_CA<3>
  VSS97  = GND
  CA5_B  = M_K_CPU0_SB_CA<5>
  VSS98  = GND
  PAR_B  = M_K_CPU0_SB_PAR
  VSS99  = GND
  CS1_B_N  = M_K_CPU0_SB_CS_N<1>
  VSS100  = GND
  RFU5  = NC
  RFU6  = NC
  VSS101  = GND
  CB6_B  = M_K_CPU0_SB_CB<6>
  VSS102  = GND
  CB7_B  = M_K_CPU0_SB_CB<7>
  VSS103  = GND
  DQS4_B_C  = M_K_CPU0_SB_DQS_DN<4>
  DQS4_B_T  = M_K_CPU0_SB_DQS_DP<4>
  VSS104  = GND
  CB2_B  = M_K_CPU0_SB_CB<2>
  VSS105  = GND
  CB3_B  = M_K_CPU0_SB_CB<3>
  VSS106  = GND
  DQ2_B  = M_K_CPU0_SB_DQ<2>
  VSS107  = GND
  DQ3_B  = M_K_CPU0_SB_DQ<3>
  VSS108  = GND
  \dqs5_b_c||tdqs5_b_c\  = M_K_CPU0_SB_DQS_DN<5>
  \dqs5_b_t||tdqs5_b_t\  = M_K_CPU0_SB_DQS_DP<5>
  VSS109  = GND
  DQ6_B  = M_K_CPU0_SB_DQ<6>
  VSS110  = GND
  DQ7_B  = M_K_CPU0_SB_DQ<7>
  VSS111  = GND
  DQ10_B  = M_K_CPU0_SB_DQ<10>
  VSS112  = GND
  DQ11_B  = M_K_CPU0_SB_DQ<11>
  VSS113  = GND
  \dqs6_b_c||tdqs6_b_c\  = M_K_CPU0_SB_DQS_DN<6>
  \dqs6_b_t||tdqs6_b_t\  = M_K_CPU0_SB_DQS_DP<6>
  VSS114  = GND
  DQ14_B  = M_K_CPU0_SB_DQ<14>
  VSS115  = GND
  DQ15_B  = M_K_CPU0_SB_DQ<15>
  VSS116  = GND
  DQ18_B  = M_K_CPU0_SB_DQ<18>
  VSS117  = GND
  DQ19_B  = M_K_CPU0_SB_DQ<19>
  VSS118  = GND
  \dqs7_b_c||tdqs7_b_c\  = M_K_CPU0_SB_DQS_DN<7>
  \dqs7_b_t||tdqs7_b_t\  = M_K_CPU0_SB_DQS_DP<7>
  VSS119  = GND
  DQ22_B  = M_K_CPU0_SB_DQ<22>
  VSS120  = GND
  DQ23_B  = M_K_CPU0_SB_DQ<23>
  VSS121  = GND
  DQ26_B  = M_K_CPU0_SB_DQ<26>
  VSS122  = GND
  DQ27_B  = M_K_CPU0_SB_DQ<27>
  VSS123  = GND
  \dqs8_b_c||tdqs8_b_c\  = M_K_CPU0_SB_DQS_DN<8>
  \dqs8_b_t||tdqs8_b_t\  = M_K_CPU0_SB_DQS_DP<8>
  VSS124  = GND
  DQ30_B  = M_K_CPU0_SB_DQ<30>
  VSS125  = GND
  DQ31_B  = M_K_CPU0_SB_DQ<31>
  VSS126  = GND
  G1  = GND
  G2  = GND
  G3  = GND

(kicad_pcb
	(version 20260206)
	(generator "pcbnew")
	(generator_version "10.0")
	(general
		(thickness 1.6)
		(legacy_teardrops no)
	)
	(paper "A4")
	(title_block
		(title "04192023_DAF0TMB3IC0_F0TG_MB_C_brd_V02_OCP.brd")
		(comment 1 "Grand Teton / footprint 2165 of 8354 (J20), pads 277-291 of 291")
	)
	(layers
		(0 "F.Cu" signal "TOP")
		(4 "In1.Cu" signal "GND")
		(6 "In2.Cu" signal "IN1")
		(8 "In3.Cu" signal "GND1")
		(10 "In4.Cu" signal "IN2")
		(12 "In5.Cu" signal "GND2")
		(14 "In6.Cu" signal "IN3")
		(16 "In7.Cu" signal "GND3")
		(18 "In8.Cu" signal "VCC")
		(20 "In9.Cu" signal "VCC1")
		(22 "In10.Cu" signal "GND4")
		(24 "In11.Cu" signal "IN4")
		(26 "In12.Cu" signal "GND5")
		(28 "In13.Cu" signal "IN5")
		(30 "In14.Cu" signal "GND6")
		(32 "In15.Cu" signal "IN6")
		(34 "In16.Cu" signal "GND7")
		(2 "B.Cu" signal "BOTTOM")
		(9 "F.Adhes" user "F.Adhesive")
		(11 "B.Adhes" user "B.Adhesive")
		(13 "F.Paste" user "Package Geometry/Pastemask Top")
		(15 "B.Paste" user "Package Geometry/Pastemask Bottom")
		(5 "F.SilkS" user "Ref Des/Silkscreen Top")
		(7 "B.SilkS" user "Ref Des/Silkscreen Bottom")
		(1 "F.Mask" user "Board Geometry/Soldermask Top")
		(3 "B.Mask" user "Board Geometry/Soldermask Bottom")
		(17 "Dwgs.User" user "User.Drawings")
		(19 "Cmts.User" user "User.Comments")
		(21 "Eco1.User" user "User.Eco1")
		(23 "Eco2.User" user "User.Eco2")
		(25 "Edge.Cuts" user "Board Geometry/Outline")
		(27 "Margin" user)
		(31 "F.CrtYd" user "Package Geometry/Place Bound Top")
		(29 "B.CrtYd" user "Package Geometry/Place Bound Bottom")
		(35 "F.Fab" user "Ref Des/Assembly Top")
		(33 "B.Fab" user "Ref Des/Assembly Bottom")
	)
	(footprint ""
		(layer "F.Cu")
		(at 444.594234 -255.560068 180)
		(property "Reference" "J20"
			(at 1.631188 -81.796128 0)
			(unlocked yes)
			(layer "F.SilkS")
			(effects
				(font
					(size 0.7874 0.5842)
					(thickness 0.1524)
				)
			)
		)
		(property "Value" ""
			(at 0 0 180)
			(layer "F.Fab")
			(effects
				(font
					(size 1.27 1.27)
				)
			)
		)
		(duplicate_pad_numbers_are_jumpers no)
		(pad "277" smd rect
			(at 2.050034 53.975 90)
			(size 0.519938 1.4986)
			(layers "F.Cu" "F.Mask" "F.Paste")
			(net "GND")
		)
		(pad "278" smd rect
			(at 2.050034 54.824884 90)
			(size 0.519938 1.4986)
			(layers "F.Cu" "F.Mask" "F.Paste")
			(net "M_K_CPU0_SB_DQ<26>")
		)
		(pad "279" smd rect
			(at 2.050034 55.675022 90)
			(size 0.519938 1.4986)
			(layers "F.Cu" "F.Mask" "F.Paste")
			(net "GND")
		)
		(pad "280" smd rect
			(at 2.050034 56.524906 90)
			(size 0.519938 1.4986)
			(layers "F.Cu" "F.Mask" "F.Paste")
			(net "M_K_CPU0_SB_DQ<27>")
		)
		(pad "281" smd rect
			(at 2.050034 57.375044 90)
			(size 0.519938 1.4986)
			(layers "F.Cu" "F.Mask" "F.Paste")
			(net "GND")
		)
		(pad "282" smd rect
			(at 2.050034 58.224928 90)
			(size 0.519938 1.4986)
			(layers "F.Cu" "F.Mask" "F.Paste")
			(net "M_K_CPU0_SB_DQS_DN<8>")
		)
		(pad "283" smd rect
			(at 2.050034 59.075066 90)
			(size 0.519938 1.4986)
			(layers "F.Cu" "F.Mask" "F.Paste")
			(net "M_K_CPU0_SB_DQS_DP<8>")
		)
		(pad "284" smd rect
			(at 2.050034 59.92495 90)
			(size 0.519938 1.4986)
			(layers "F.Cu" "F.Mask" "F.Paste")
			(net "GND")
		)
		(pad "285" smd rect
			(at 2.050034 60.775088 90)
			(size 0.519938 1.4986)
			(layers "F.Cu" "F.Mask" "F.Paste")
			(net "M_K_CPU0_SB_DQ<30>")
		)
		(pad "286" smd rect
			(at 2.050034 61.624972 90)
			(size 0.519938 1.4986)
			(layers "F.Cu" "F.Mask" "F.Paste")
			(net "GND")
		)
		(pad "287" smd rect
			(at 2.050034 62.47511 90)
			(size 0.519938 1.4986)
			(layers "F.Cu" "F.Mask" "F.Paste")
			(net "M_K_CPU0_SB_DQ<31>")
		)
		(pad "288" smd rect
			(at 2.050034 63.324994 90)
			(size 0.519938 1.4986)
			(layers "F.Cu" "F.Mask" "F.Paste")
			(net "GND")
		)
		(pad "G1" thru_hole oval
			(at 0 -68.97497 90)
			(size 1.7272 3.4798)
			(drill oval 1.2192 2.4638)
			(layers "*.Cu" "*.Mask")
			(remove_unused_layers no)
			(net "GND")
			(clearance 0.127)
			(thermal_gap 0.127)
		)
		(pad "G2" thru_hole oval
			(at 0 3.875024 90)
			(size 1.7272 3.4798)
			(drill oval 1.2192 2.4638)
			(layers "*.Cu" "*.Mask")
			(remove_unused_layers no)
			(net "GND")
			(clearance 0.127)
			(thermal_gap 0.127)
		)
		(pad "G3" thru_hole oval
			(at 0 68.97497 90)
			(size 1.7272 3.4798)
			(drill oval 1.2192 2.4638)
			(layers "*.Cu" "*.Mask")
			(remove_unused_layers no)
			(net "GND")
			(clearance 0.127)
			(thermal_gap 0.127)
		)
	)
)
